# T6G (Grand Teton) — schematic netlist excerpt (pin names and nets, part order shuffled) for the footprints in the layout excerpt that follows; sources: Cadence DE-HDL packaged netlist, KiCad conversion of 04192023_DAF0TMB3IC0_F0TG_MB_C_brd_V02_OCP.brd

PR601  Q_RES  4.99K 1% EMPTY  pkg 0402LF  page 207 : A = PVDD11_S3_P0_VINSEN ; B = GND
R1000  Q_RES  4.7K 5% CHIP  pkg 0402LF  page 145 : A = FM_LED_ACTIVE_E1S_0_BUF ; B = GND

(kicad_pcb
	(version 20260206)
	(generator "pcbnew")
	(generator_version "10.0")
	(general
		(thickness 1.6)
		(legacy_teardrops no)
	)
	(paper "A4")
	(title_block
		(title "04192023_DAF0TMB3IC0_F0TG_MB_C_brd_V02_OCP.brd")
		(comment 1 "Grand Teton / footprints 2601-2602 of 8354")
	)
	(layers
		(0 "F.Cu" signal "TOP")
		(4 "In1.Cu" signal "GND")
		(6 "In2.Cu" signal "IN1")
		(8 "In3.Cu" signal "GND1")
		(10 "In4.Cu" signal "IN2")
		(12 "In5.Cu" signal "GND2")
		(14 "In6.Cu" signal "IN3")
		(16 "In7.Cu" signal "GND3")
		(18 "In8.Cu" signal "VCC")
		(20 "In9.Cu" signal "VCC1")
		(22 "In10.Cu" signal "GND4")
		(24 "In11.Cu" signal "IN4")
		(26 "In12.Cu" signal "GND5")
		(28 "In13.Cu" signal "IN5")
		(30 "In14.Cu" signal "GND6")
		(32 "In15.Cu" signal "IN6")
		(34 "In16.Cu" signal "GND7")
		(2 "B.Cu" signal "BOTTOM")
		(9 "F.Adhes" user "F.Adhesive")
		(11 "B.Adhes" user "B.Adhesive")
		(13 "F.Paste" user "Package Geometry/Pastemask Top")
		(15 "B.Paste" user "Package Geometry/Pastemask Bottom")
		(5 "F.SilkS" user "Ref Des/Silkscreen Top")
		(7 "B.SilkS" user "Ref Des/Silkscreen Bottom")
		(1 "F.Mask" user "Board Geometry/Soldermask Top")
		(3 "B.Mask" user "Board Geometry/Soldermask Bottom")
		(17 "Dwgs.User" user "User.Drawings")
		(19 "Cmts.User" user "User.Comments")
		(21 "Eco1.User" user "User.Eco1")
		(23 "Eco2.User" user "User.Eco2")
		(25 "Edge.Cuts" user "Board Geometry/Outline")
		(27 "Margin" user)
		(31 "F.CrtYd" user "Package Geometry/Place Bound Top")
		(29 "B.CrtYd" user "Package Geometry/Place Bound Bottom")
		(35 "F.Fab" user "Ref Des/Assembly Top")
		(33 "B.Fab" user "Ref Des/Assembly Bottom")
	)
	(footprint ""
		(layer "F.Cu")
		(at 232.732072 -69.560186 90)
		(property "Reference" "R1000"
			(at 0 0 90)
			(layer "F.SilkS")
			(hide yes)
			(effects
				(font
					(size 1.27 1.27)
				)
			)
		)
		(property "Value" ""
			(at 0 0 90)
			(layer "F.Fab")
			(effects
				(font
					(size 1.27 1.27)
				)
			)
		)
		(duplicate_pad_numbers_are_jumpers no)
		(fp_line
			(start 0.7874 -0.4064)
			(end 0.7874 0.4064)
			(stroke
				(width 0.1524)
				(type default)
			)
			(layer "F.SilkS")
		)
		(fp_line
			(start -0.7874 -0.4064)
			(end 0.7874 -0.4064)
			(stroke
				(width 0.1524)
				(type default)
			)
			(layer "F.SilkS")
		)
		(fp_line
			(start 0.7874 0.4064)
			(end -0.7874 0.4064)
			(stroke
				(width 0.1524)
				(type default)
			)
			(layer "F.SilkS")
		)
		(fp_line
			(start -0.7874 0.4064)
			(end -0.7874 -0.4064)
			(stroke
				(width 0.1524)
				(type default)
			)
			(layer "F.SilkS")
		)
		(fp_line
			(start -0.12065 -0.305054)
			(end -0.12065 -0.2794)
			(stroke
				(width 0.1)
				(type default)
			)
			(layer "F.Fab")
		)
		(fp_line
			(start -0.67945 -0.305054)
			(end -0.12065 -0.305054)
			(stroke
				(width 0.1)
				(type default)
			)
			(layer "F.Fab")
		)
		(fp_line
			(start 0.67945 -0.3048)
			(end 0.67945 0.3048)
			(stroke
				(width 0.1)
				(type default)
			)
			(layer "F.Fab")
		)
		(fp_line
			(start 0.12065 -0.3048)
			(end 0.67945 -0.3048)
			(stroke
				(width 0.1)
				(type default)
			)
			(layer "F.Fab")
		)
		(fp_line
			(start 0.12065 -0.2794)
			(end 0.12065 -0.3048)
			(stroke
				(width 0.1)
				(type default)
			)
			(layer "F.Fab")
		)
		(fp_line
			(start -0.12065 -0.2794)
			(end 0.12065 -0.2794)
			(stroke
				(width 0.1)
				(type default)
			)
			(layer "F.Fab")
		)
		(fp_line
			(start 0.120396 0.2794)
			(end -0.12065 0.2794)
			(stroke
				(width 0.1)
				(type default)
			)
			(layer "F.Fab")
		)
		(fp_line
			(start -0.12065 0.2794)
			(end -0.12065 0.3048)
			(stroke
				(width 0.1)
				(type default)
			)
			(layer "F.Fab")
		)
		(fp_line
			(start 0.67945 0.3048)
			(end 0.120396 0.3048)
			(stroke
				(width 0.1)
				(type default)
			)
			(layer "F.Fab")
		)
		(fp_line
			(start 0.120396 0.3048)
			(end 0.120396 0.2794)
			(stroke
				(width 0.1)
				(type default)
			)
			(layer "F.Fab")
		)
		(fp_line
			(start -0.12065 0.3048)
			(end -0.67945 0.3048)
			(stroke
				(width 0.1)
				(type default)
			)
			(layer "F.Fab")
		)
		(fp_line
			(start -0.67945 0.3048)
			(end -0.67945 -0.305054)
			(stroke
				(width 0.1)
				(type default)
			)
			(layer "F.Fab")
		)
		(pad "1" smd circle
			(at -0.40005 0 90)
			(size 0 0)
			(layers "F.Cu" "F.Mask" "F.Paste")
			(net "FM_LED_ACTIVE_E1S_0_BUF")
		)
		(pad "2" smd circle
			(at 0.40005 0 90)
			(size 0 0)
			(layers "F.Cu" "F.Mask" "F.Paste")
			(net "GND")
		)
	)
	(footprint ""
		(layer "F.Cu")
		(at 426.974 -364.49 -90)
		(property "Reference" "PR601"
			(at 0 0 270)
			(layer "F.SilkS")
			(hide yes)
			(effects
				(font
					(size 1.27 1.27)
				)
			)
		)
		(property "Value" ""
			(at 0 0 270)
			(layer "F.Fab")
			(effects
				(font
					(size 1.27 1.27)
				)
			)
		)
		(duplicate_pad_numbers_are_jumpers no)
		(fp_line
			(start -0.7874 0.4064)
			(end -0.7874 -0.4064)
			(stroke
				(width 0.1524)
				(type default)
			)
			(layer "F.SilkS")
		)
		(fp_line
			(start 0.7874 0.4064)
			(end -0.7874 0.4064)
			(stroke
				(width 0.1524)
				(type default)
			)
			(layer "F.SilkS")
		)
		(fp_line
			(start -0.7874 -0.4064)
			(end 0.7874 -0.4064)
			(stroke
				(width 0.1524)
				(type default)
			)
			(layer "F.SilkS")
		)
		(fp_line
			(start 0.7874 -0.4064)
			(end 0.7874 0.4064)
			(stroke
				(width 0.1524)
				(type default)
			)
			(layer "F.SilkS")
		)
		(fp_line
			(start -0.67945 0.3048)
			(end -0.67945 -0.305054)
			(stroke
				(width 0.1)
				(type default)
			)
			(layer "F.Fab")
		)
		(fp_line
			(start -0.12065 0.3048)
			(end -0.67945 0.3048)
			(stroke
				(width 0.1)
				(type default)
			)
			(layer "F.Fab")
		)
		(fp_line
			(start 0.120396 0.3048)
			(end 0.120396 0.2794)
			(stroke
				(width 0.1)
				(type default)
			)
			(layer "F.Fab")
		)
		(fp_line
			(start 0.67945 0.3048)
			(end 0.120396 0.3048)
			(stroke
				(width 0.1)
				(type default)
			)
			(layer "F.Fab")
		)
		(fp_line
			(start -0.12065 0.2794)
			(end -0.12065 0.3048)
			(stroke
				(width 0.1)
				(type default)
			)
			(layer "F.Fab")
		)
		(fp_line
			(start 0.120396 0.2794)
			(end -0.12065 0.2794)
			(stroke
				(width 0.1)
				(type default)
			)
			(layer "F.Fab")
		)
		(fp_line
			(start -0.12065 -0.2794)
			(end 0.12065 -0.2794)
			(stroke
				(width 0.1)
				(type default)
			)
			(layer "F.Fab")
		)
		(fp_line
			(start 0.12065 -0.2794)
			(end 0.12065 -0.3048)
			(stroke
				(width 0.1)
				(type default)
			)
			(layer "F.Fab")
		)
		(fp_line
			(start 0.12065 -0.3048)
			(end 0.67945 -0.3048)
			(stroke
				(width 0.1)
				(type default)
			)
			(layer "F.Fab")
		)
		(fp_line
			(start 0.67945 -0.3048)
			(end 0.67945 0.3048)
			(stroke
				(width 0.1)
				(type default)
			)
			(layer "F.Fab")
		)
		(fp_line
			(start -0.67945 -0.305054)
			(end -0.12065 -0.305054)
			(stroke
				(width 0.1)
				(type default)
			)
			(layer "F.Fab")
		)
		(fp_line
			(start -0.12065 -0.305054)
			(end -0.12065 -0.2794)
			(stroke
				(width 0.1)
				(type default)
			)
			(layer "F.Fab")
		)
		(pad "1" smd circle
			(at -0.40005 0 270)
			(size 0 0)
			(layers "F.Cu" "F.Mask" "F.Paste")
			(net "PVDD11_S3_P0_VINSEN")
		)
		(pad "2" smd circle
			(at 0.40005 0 270)
			(size 0 0)
			(layers "F.Cu" "F.Mask" "F.Paste")
			(net "GND")
		)
	)
)
